(kicad_pcb
	(version 20260206)
	(generator "pcbnew")
	(generator_version "10.0")
	(general
		(thickness 1.6)
		(legacy_teardrops no)
	)
	(paper "A4")
	(title_block
		(title "Bryce Canyon_R.DPB_16317-1_OCP.brd")
		(comment 1 "Bryce Canyon / footprints 1962-1967 of 2099")
	)
	(layers
		(0 "F.Cu" signal "TOP")
		(4 "In1.Cu" signal "L2GND")
		(6 "In2.Cu" signal "L3")
		(8 "In3.Cu" signal "L4VCC")
		(10 "In4.Cu" signal "L5VCC")
		(12 "In5.Cu" signal "L6")
		(14 "In6.Cu" signal "L7GND")
		(2 "B.Cu" signal "BOTTOM")
		(9 "F.Adhes" user "F.Adhesive")
		(11 "B.Adhes" user "B.Adhesive")
		(13 "F.Paste" user "Package Geometry/Pastemask Top")
		(15 "B.Paste" user "Package Geometry/Pastemask Bottom")
		(5 "F.SilkS" user "Ref Des/Silkscreen Top")
		(7 "B.SilkS" user "Ref Des/Silkscreen Bottom")
		(1 "F.Mask" user "Board Geometry/Soldermask Top")
		(3 "B.Mask" user "Board Geometry/Soldermask Bottom")
		(17 "Dwgs.User" user "User.Drawings")
		(19 "Cmts.User" user "User.Comments")
		(21 "Eco1.User" user "User.Eco1")
		(23 "Eco2.User" user "User.Eco2")
		(25 "Edge.Cuts" user "Board Geometry/Outline")
		(27 "Margin" user)
		(31 "F.CrtYd" user "Package Geometry/Place Bound Top")
		(29 "B.CrtYd" user "Package Geometry/Place Bound Bottom")
		(35 "F.Fab" user "Ref Des/Assembly Top")
		(33 "B.Fab" user "Ref Des/Assembly Bottom")
	)
	(footprint ""
		(layer "B.Cu")
		(at 167.7162 -369.189 90)
		(property "Reference" "R1059"
			(at 0 0 90)
			(layer "B.SilkS")
			(hide yes)
			(effects
				(font
					(size 1.27 1.27)
				)
				(justify mirror)
			)
		)
		(property "Value" "10R2F-L-GP"
			(at -0.064008 -3.993896 90)
			(unlocked yes)
			(layer "B.Fab")
			(hide yes)
			(effects
				(font
					(size 1.016 1.016)
					(thickness 0.1524)
				)
				(justify mirror)
			)
		)
		(property "Device Type" "R402H14"
			(at -0.064008 -5.517896 90)
			(unlocked yes)
			(layer "B.Fab")
			(hide yes)
			(effects
				(font
					(size 1.016 1.016)
					(thickness 0.1524)
				)
				(justify mirror)
			)
		)
		(duplicate_pad_numbers_are_jumpers no)
		(fp_line
			(start 0.508 -0.9398)
			(end 0.508 0.9398)
			(stroke
				(width 0.1524)
				(type default)
			)
			(layer "B.SilkS")
		)
		(fp_line
			(start -0.508 -0.9398)
			(end 0.508 -0.9398)
			(stroke
				(width 0.1524)
				(type default)
			)
			(layer "B.SilkS")
		)
		(fp_rect
			(start 0.508 0.9398)
			(end -0.508 -0.9398)
			(stroke
				(width 0)
				(type default)
			)
			(fill no)
			(layer "B.CrtYd")
		)
		(fp_rect
			(start 0.508 0.9398)
			(end -0.508 -0.9398)
			(stroke
				(width 0)
				(type default)
			)
			(fill no)
			(layer "B.Fab")
		)
		(pad "1" smd custom
			(at 0 -0.4445 270)
			(size 0.1397 0.1397)
			(layers "B.Cu" "B.Mask" "B.Paste")
			(net "MB0_CM_SENSE_R1_P")
			(options
				(clearance outline)
				(anchor circle)
			)
			(primitives
				(gr_poly
					(pts
						(arc
							(start -0.1778 0.2794)
							(mid -0.249642 0.249642)
							(end -0.2794 0.1778)
						)
						(arc
							(start -0.2794 -0.1778)
							(mid -0.249642 -0.249642)
							(end -0.1778 -0.2794)
						)
						(arc
							(start 0.1778 -0.2794)
							(mid 0.249642 -0.249642)
							(end 0.2794 -0.1778)
						)
						(arc
							(start 0.2794 0.1778)
							(mid 0.249642 0.249642)
							(end 0.1778 0.2794)
						)
					)
					(width 0)
					(fill yes)
				)
			)
		)
		(pad "2" smd custom
			(at 0 0.4445 270)
			(size 0.1397 0.1397)
			(layers "B.Cu" "B.Mask" "B.Paste")
			(net "MB0_HS_SENSE_P")
			(options
				(clearance outline)
				(anchor circle)
			)
			(primitives
				(gr_poly
					(pts
						(arc
							(start -0.1778 0.2794)
							(mid -0.249642 0.249642)
							(end -0.2794 0.1778)
						)
						(arc
							(start -0.2794 -0.1778)
							(mid -0.249642 -0.249642)
							(end -0.1778 -0.2794)
						)
						(arc
							(start 0.1778 -0.2794)
							(mid 0.249642 -0.249642)
							(end 0.2794 -0.1778)
						)
						(arc
							(start 0.2794 0.1778)
							(mid 0.249642 0.249642)
							(end 0.1778 0.2794)
						)
					)
					(width 0)
					(fill yes)
				)
			)
		)
	)
	(footprint ""
		(layer "B.Cu")
		(at 456.733402 -229.54615)
		(property "Reference" "G6"
			(at 0 0 0)
			(layer "B.SilkS")
			(hide yes)
			(effects
				(font
					(size 1.27 1.27)
				)
				(justify mirror)
			)
		)
		(property "Value" "COPPER-CLOSE-GP-U"
			(at -0.0762 -2.8702 0)
			(unlocked yes)
			(layer "B.Fab")
			(hide yes)
			(effects
				(font
					(size 1.016 1.016)
					(thickness 0.1524)
				)
				(justify mirror)
			)
		)
		(property "Device Type" "CON2C-U"
			(at -0.0762 -4.3942 0)
			(unlocked yes)
			(layer "B.Fab")
			(hide yes)
			(effects
				(font
					(size 1.016 1.016)
					(thickness 0.1524)
				)
				(justify mirror)
			)
		)
		(duplicate_pad_numbers_are_jumpers no)
		(fp_rect
			(start 0.9398 0.9652)
			(end -0.9398 -0.9652)
			(stroke
				(width 0)
				(type default)
			)
			(fill no)
			(layer "B.CrtYd")
		)
		(fp_rect
			(start 0.9398 0.9652)
			(end -0.9398 -0.9652)
			(stroke
				(width 0)
				(type default)
			)
			(fill no)
			(layer "B.Fab")
		)
		(pad "1" smd custom
			(at 0 -0.5334 180)
			(size 0.17145 0.17145)
			(layers "B.Cu" "B.Mask" "B.Paste")
			(net "AGND_P5V_B_3")
			(options
				(clearance outline)
				(anchor circle)
			)
			(primitives
				(gr_poly
					(pts
						(xy -0.127 -0.3429) (xy -0.127 -0.1651) (xy -0.635 0.3429) (xy 0.635 0.3429) (xy 0.127 -0.1651)
						(xy 0.127 -0.3429)
					)
					(width 0)
					(fill yes)
				)
			)
		)
		(pad "2" smd custom
			(at 0 0.5334 180)
			(size 0.17145 0.17145)
			(layers "B.Cu" "B.Mask" "B.Paste")
			(net "GND")
			(options
				(clearance outline)
				(anchor circle)
			)
			(primitives
				(gr_poly
					(pts
						(xy -0.635 -0.3429) (xy -0.127 0.1651) (xy -0.127 0.3429) (xy 0.127 0.3429) (xy 0.127 0.1651)
						(xy 0.635 -0.3429)
					)
					(width 0)
					(fill yes)
				)
			)
		)
	)
	(footprint ""
		(layer "B.Cu")
		(at 46.438058 -113.732056 -90)
		(property "Reference" "U32"
			(at 0 0 90)
			(layer "B.SilkS")
			(hide yes)
			(effects
				(font
					(size 1.27 1.27)
				)
				(justify mirror)
			)
		)
		(property "Value" "TPS53319DQPR-GP"
			(at -4.7498 -5.6896 270)
			(unlocked yes)
			(layer "B.Fab")
			(hide yes)
			(effects
				(font
					(size 1.016 1.016)
					(thickness 0.1524)
				)
				(justify mirror)
			)
		)
		(property "Device Type" "QFN22G6050-G6133H60"
			(at -4.7498 -7.2136 270)
			(unlocked yes)
			(layer "B.Fab")
			(hide yes)
			(effects
				(font
					(size 1.016 1.016)
					(thickness 0.1524)
				)
				(justify mirror)
			)
		)
		(duplicate_pad_numbers_are_jumpers no)
		(fp_line
			(start -3.556 3.5179)
			(end -3.556 2.2479)
			(stroke
				(width 0.1524)
				(type default)
			)
			(layer "B.SilkS")
		)
		(fp_line
			(start -2.286 3.5179)
			(end -3.556 3.5179)
			(stroke
				(width 0.1524)
				(type default)
			)
			(layer "B.SilkS")
		)
		(fp_line
			(start 3.556 3.5179)
			(end 2.286 3.5179)
			(stroke
				(width 0.1524)
				(type default)
			)
			(layer "B.SilkS")
		)
		(fp_line
			(start -1.500124 3.262122)
			(end -1.500124 4.024122)
			(stroke
				(width 0.1524)
				(type default)
			)
			(layer "B.SilkS")
		)
		(fp_line
			(start 0.999998 3.262122)
			(end 0.999998 3.770122)
			(stroke
				(width 0.1524)
				(type default)
			)
			(layer "B.SilkS")
		)
		(fp_line
			(start 3.556 2.2479)
			(end 3.556 3.5179)
			(stroke
				(width 0.1524)
				(type default)
			)
			(layer "B.SilkS")
		)
		(fp_line
			(start -0.500126 -3.262122)
			(end -0.500126 -3.770122)
			(stroke
				(width 0.1524)
				(type default)
			)
			(layer "B.SilkS")
		)
		(fp_line
			(start 1.999996 -3.262122)
			(end 1.999996 -4.024122)
			(stroke
				(width 0.1524)
				(type default)
			)
			(layer "B.SilkS")
		)
		(fp_line
			(start 2.286 -3.5179)
			(end 3.556 -3.5179)
			(stroke
				(width 0.1524)
				(type default)
			)
			(layer "B.SilkS")
		)
		(fp_line
			(start 3.556 -3.5179)
			(end 3.556 -2.2479)
			(stroke
				(width 0.1524)
				(type default)
			)
			(layer "B.SilkS")
		)
		(fp_poly
			(pts
				(xy -3.556 -3.5179) (xy -2.5273 -3.5179) (xy -3.556 -2.4892)
			)
			(stroke
				(width 0)
				(type default)
			)
			(fill yes)
			(layer "B.SilkS")
		)
		(fp_rect
			(start 2.9972 2.5019)
			(end -2.9972 -2.5019)
			(stroke
				(width 0)
				(type default)
			)
			(fill no)
			(layer "B.CrtYd")
		)
		(fp_poly
			(pts
				(xy -3.556 -2.5019) (xy 2.9972 -2.5019) (xy 2.9972 2.5019) (xy -2.9972 2.5019) (xy -2.9972 -2.4892)
				(xy -3.556 -2.4892) (xy -3.556 3.5179) (xy 3.556 3.5179) (xy 3.556 -3.5179) (xy -3.556 -3.5179)
			)
			(stroke
				(width 0)
				(type default)
			)
			(fill no)
			(layer "B.CrtYd")
		)
		(fp_rect
			(start 3.556 3.5179)
			(end -3.556 -3.5179)
			(stroke
				(width 0)
				(type default)
			)
			(fill no)
			(layer "B.Fab")
		)
		(pad "1" smd rect
			(at -2.500122 -2.449322 90)
			(size 0.3048 1.1176)
			(layers "B.Cu" "B.Mask" "B.Paste")
			(net "P5V_B_2_VFB")
		)
		(pad "2" smd rect
			(at -1.999996 -2.449322 90)
			(size 0.3048 1.1176)
			(layers "B.Cu" "B.Mask" "B.Paste")
			(net "P5V_B_2_EN_R")
		)
		(pad "3" smd rect
			(at -1.500124 -2.449322 90)
			(size 0.3048 1.1176)
			(layers "B.Cu" "B.Mask" "B.Paste")
			(net "P5V_B_2_PGOOD")
		)
		(pad "4" smd rect
			(at -0.999998 -2.449322 90)
			(size 0.3048 1.1176)
			(layers "B.Cu" "B.Mask" "B.Paste")
			(net "P5V_B_2_VBST")
		)
		(pad "5" smd rect
			(at -0.500126 -2.449322 90)
			(size 0.3048 1.1176)
			(layers "B.Cu" "B.Mask" "B.Paste")
			(net "P5V_B_2_ROVP")
		)
		(pad "6" smd rect
			(at 0 -2.449322 90)
			(size 0.3048 1.1176)
			(layers "B.Cu" "B.Mask" "B.Paste")
			(net "P5V_B_2_LL")
		)
		(pad "7" smd rect
			(at 0.500126 -2.449322 90)
			(size 0.3048 1.1176)
			(layers "B.Cu" "B.Mask" "B.Paste")
			(net "P5V_B_2_LL")
		)
		(pad "8" smd rect
			(at 0.999998 -2.449322 90)
			(size 0.3048 1.1176)
			(layers "B.Cu" "B.Mask" "B.Paste")
			(net "P5V_B_2_LL")
		)
		(pad "9" smd rect
			(at 1.500124 -2.449322 90)
			(size 0.3048 1.1176)
			(layers "B.Cu" "B.Mask" "B.Paste")
			(net "P5V_B_2_LL")
		)
		(pad "10" smd rect
			(at 1.999996 -2.449322 90)
			(size 0.3048 1.1176)
			(layers "B.Cu" "B.Mask" "B.Paste")
			(net "P5V_B_2_LL")
		)
		(pad "11" smd rect
			(at 2.500122 -2.449322 90)
			(size 0.3048 1.1176)
			(layers "B.Cu" "B.Mask" "B.Paste")
			(net "P5V_B_2_LL")
		)
		(pad "12" smd rect
			(at 2.500122 2.449322 90)
			(size 0.3048 1.1176)
			(layers "B.Cu" "B.Mask" "B.Paste")
			(net "P12V_B_2_VIN_U32")
		)
		(pad "13" smd rect
			(at 1.999996 2.449322 90)
			(size 0.3048 1.1176)
			(layers "B.Cu" "B.Mask" "B.Paste")
			(net "P12V_B_2_VIN_U32")
		)
		(pad "14" smd rect
			(at 1.500124 2.449322 90)
			(size 0.3048 1.1176)
			(layers "B.Cu" "B.Mask" "B.Paste")
			(net "P12V_B_2_VIN_U32")
		)
		(pad "15" smd rect
			(at 0.999998 2.449322 90)
			(size 0.3048 1.1176)
			(layers "B.Cu" "B.Mask" "B.Paste")
			(net "P12V_B_2_VIN_U32")
		)
		(pad "16" smd rect
			(at 0.500126 2.449322 90)
			(size 0.3048 1.1176)
			(layers "B.Cu" "B.Mask" "B.Paste")
			(net "P12V_B_2_VIN_U32")
		)
		(pad "17" smd rect
			(at 0 2.449322 90)
			(size 0.3048 1.1176)
			(layers "B.Cu" "B.Mask" "B.Paste")
			(net "P12V_B_2_VIN_U32")
		)
		(pad "18" smd rect
			(at -0.500126 2.449322 90)
			(size 0.3048 1.1176)
			(layers "B.Cu" "B.Mask" "B.Paste")
			(net "P5V_B_2_VREG")
		)
		(pad "19" smd rect
			(at -0.999998 2.449322 90)
			(size 0.3048 1.1176)
			(layers "B.Cu" "B.Mask" "B.Paste")
			(net "P12V_B_2_VDD_U32")
		)
		(pad "20" smd rect
			(at -1.500124 2.449322 90)
			(size 0.3048 1.1176)
			(layers "B.Cu" "B.Mask" "B.Paste")
			(net "P5V_B_2_MODE")
		)
		(pad "21" smd rect
			(at -1.999996 2.449322 90)
			(size 0.3048 1.1176)
			(layers "B.Cu" "B.Mask" "B.Paste")
			(net "P5V_B_2_TRIP")
		)
		(pad "22" smd rect
			(at -2.500122 2.449322 90)
			(size 0.3048 1.1176)
			(layers "B.Cu" "B.Mask" "B.Paste")
			(net "P5V_B_2_RF")
		)
		(pad "23" smd custom
			(at 0 0 90)
			(size 0.83185 0.83185)
			(layers "B.Cu" "B.Mask" "B.Paste")
			(net "GND")
			(options
				(clearance outline)
				(anchor circle)
			)
			(primitives
				(gr_poly
					(pts
						(xy -2.7813 -1.6637) (xy -2.7813 -1.2954) (xy -3.048 -1.2954) (xy -3.048 -0.9525) (xy -2.7813 -0.9525)
						(xy -2.7813 0.9525) (xy -3.048 0.9525) (xy -3.048 1.2954) (xy -2.7813 1.2954) (xy -2.7813 1.6637)
						(xy 2.7813 1.6637) (xy 2.7813 1.2954) (xy 3.048 1.2954) (xy 3.048 0.9525) (xy 2.7813 0.9525) (xy 2.7813 -0.9525)
						(xy 3.048 -0.9525) (xy 3.048 -1.2954) (xy 2.7813 -1.2954) (xy 2.7813 -1.6637)
					)
					(width 0)
					(fill yes)
				)
			)
		)
	)
	(footprint ""
		(layer "B.Cu")
		(at 74.95286 -117.040406 -90)
		(property "Reference" "G3"
			(at 0 0 90)
			(layer "B.SilkS")
			(hide yes)
			(effects
				(font
					(size 1.27 1.27)
				)
				(justify mirror)
			)
		)
		(property "Value" "GAP-CLOSE-PWR-4-GP"
			(at 2.4638 -0.5461 270)
			(unlocked yes)
			(layer "B.Fab")
			(hide yes)
			(effects
				(font
					(size 1.016 1.016)
					(thickness 0.1524)
				)
				(justify mirror)
			)
		)
		(property "Device Type" "GAP-CLOSE-PWR-4"
			(at 2.4638 -2.0701 270)
			(unlocked yes)
			(layer "B.Fab")
			(hide yes)
			(effects
				(font
					(size 1.016 1.016)
					(thickness 0.1524)
				)
				(justify mirror)
			)
		)
		(duplicate_pad_numbers_are_jumpers no)
		(fp_rect
			(start 0.2794 0.254)
			(end -0.2794 -0.254)
			(stroke
				(width 0)
				(type default)
			)
			(fill no)
			(layer "B.CrtYd")
		)
		(fp_rect
			(start 0.2794 0.254)
			(end -0.2794 -0.254)
			(stroke
				(width 0)
				(type default)
			)
			(fill no)
			(layer "B.Fab")
		)
		(pad "1" smd rect
			(at 0.0635 0 90)
			(size 0.1778 0.254)
			(layers "B.Cu" "B.Mask" "B.Paste")
			(net "P5V_B_2")
		)
		(pad "2" smd rect
			(at -0.0635 0 90)
			(size 0.1778 0.254)
			(layers "B.Cu" "B.Mask" "B.Paste")
			(net "P5V_B_2_CC")
		)
	)
	(footprint ""
		(layer "B.Cu")
		(at 443.804802 -222.51035 180)
		(property "Reference" "R1137"
			(at 0 0 0)
			(layer "B.SilkS")
			(hide yes)
			(effects
				(font
					(size 1.27 1.27)
				)
				(justify mirror)
			)
		)
		(property "Value" "2D2R3-1-U-GP"
			(at 0.0254 -2.5146 180)
			(unlocked yes)
			(layer "B.Fab")
			(hide yes)
			(effects
				(font
					(size 1.016 1.016)
					(thickness 0.1524)
				)
				(justify mirror)
			)
		)
		(property "Device Type" "R603H22"
			(at 0.0254 -4.0386 180)
			(unlocked yes)
			(layer "B.Fab")
			(hide yes)
			(effects
				(font
					(size 1.016 1.016)
					(thickness 0.1524)
				)
				(justify mirror)
			)
		)
		(duplicate_pad_numbers_are_jumpers no)
		(fp_line
			(start 0.4826 0)
			(end 0.2032 0)
			(stroke
				(width 0.2032)
				(type default)
			)
			(layer "B.SilkS")
		)
		(fp_line
			(start -0.2032 0)
			(end -0.4826 0)
			(stroke
				(width 0.2032)
				(type default)
			)
			(layer "B.SilkS")
		)
		(fp_rect
			(start 0.5842 1.3335)
			(end -0.5842 -1.3335)
			(stroke
				(width 0)
				(type default)
			)
			(fill no)
			(layer "B.CrtYd")
		)
		(fp_rect
			(start 0.5842 1.3335)
			(end -0.5842 -1.3335)
			(stroke
				(width 0)
				(type default)
			)
			(fill no)
			(layer "B.Fab")
		)
		(pad "1" smd custom
			(at 0 -0.762)
			(size 0.2159 0.2159)
			(layers "B.Cu" "B.Mask" "B.Paste")
			(net "P12V_B")
			(options
				(clearance outline)
				(anchor circle)
			)
			(primitives
				(gr_poly
					(pts
						(arc
							(start -0.3302 0.4318)
							(mid -0.402042 0.402042)
							(end -0.4318 0.3302)
						)
						(arc
							(start -0.4318 -0.3302)
							(mid -0.402042 -0.402042)
							(end -0.3302 -0.4318)
						)
						(arc
							(start 0.3302 -0.4318)
							(mid 0.402042 -0.402042)
							(end 0.4318 -0.3302)
						)
						(arc
							(start 0.4318 0.3302)
							(mid 0.402042 0.402042)
							(end 0.3302 0.4318)
						)
					)
					(width 0)
					(fill yes)
				)
			)
		)
		(pad "2" smd custom
			(at 0 0.762)
			(size 0.2159 0.2159)
			(layers "B.Cu" "B.Mask" "B.Paste")
			(net "P12V_B_3_VDD_U33")
			(options
				(clearance outline)
				(anchor circle)
			)
			(primitives
				(gr_poly
					(pts
						(arc
							(start -0.3302 0.4318)
							(mid -0.402042 0.402042)
							(end -0.4318 0.3302)
						)
						(arc
							(start -0.4318 -0.3302)
							(mid -0.402042 -0.402042)
							(end -0.3302 -0.4318)
						)
						(arc
							(start 0.3302 -0.4318)
							(mid 0.402042 -0.402042)
							(end 0.4318 -0.3302)
						)
						(arc
							(start 0.4318 0.3302)
							(mid 0.402042 0.402042)
							(end 0.3302 0.4318)
						)
					)
					(width 0)
					(fill yes)
				)
			)
		)
	)
	(footprint ""
		(layer "B.Cu")
		(at 432.526186 -112.955578 180)
		(property "Reference" "C674"
			(at 0 0 0)
			(layer "B.SilkS")
			(hide yes)
			(effects
				(font
					(size 1.27 1.27)
				)
				(justify mirror)
			)
		)
		(property "Value" "SCD1U16V2KX-3GP"
			(at -1.1811 -2.7051 180)
			(unlocked yes)
			(layer "B.Fab")
			(hide yes)
			(effects
				(font
					(size 1.016 1.016)
					(thickness 0.1524)
				)
				(justify mirror)
			)
		)
		(property "Device Type" "C402H22"
			(at -1.1811 -4.2291 180)
			(unlocked yes)
			(layer "B.Fab")
			(hide yes)
			(effects
				(font
					(size 1.016 1.016)
					(thickness 0.1524)
				)
				(justify mirror)
			)
		)
		(duplicate_pad_numbers_are_jumpers no)
		(fp_rect
			(start 0.4318 0.9525)
			(end -0.4318 -0.9525)
			(stroke
				(width 0)
				(type default)
			)
			(fill no)
			(layer "B.CrtYd")
		)
		(fp_rect
			(start 0.4318 0.9525)
			(end -0.4318 -0.9525)
			(stroke
				(width 0)
				(type default)
			)
			(fill no)
			(layer "B.Fab")
		)
		(pad "1" smd custom
			(at 0 -0.4445)
			(size 0.1524 0.1524)
			(layers "B.Cu" "B.Mask" "B.Paste")
			(net "P12V_B_4_VIN_U34")
			(options
				(clearance outline)
				(anchor circle)
			)
			(primitives
				(gr_poly
					(pts
						(arc
							(start 0.3048 0.2032)
							(mid 0.275042 0.275042)
							(end 0.2032 0.3048)
						)
						(arc
							(start -0.2032 0.3048)
							(mid -0.275042 0.275042)
							(end -0.3048 0.2032)
						)
						(arc
							(start -0.3048 -0.2032)
							(mid -0.275042 -0.275042)
							(end -0.2032 -0.3048)
						)
						(arc
							(start 0.2032 -0.3048)
							(mid 0.275042 -0.275042)
							(end 0.3048 -0.2032)
						)
					)
					(width 0)
					(fill yes)
				)
			)
		)
		(pad "2" smd custom
			(at 0 0.4445)
			(size 0.1524 0.1524)
			(layers "B.Cu" "B.Mask" "B.Paste")
			(net "GND")
			(options
				(clearance outline)
				(anchor circle)
			)
			(primitives
				(gr_poly
					(pts
						(arc
							(start 0.3048 0.2032)
							(mid 0.275042 0.275042)
							(end 0.2032 0.3048)
						)
						(arc
							(start -0.2032 0.3048)
							(mid -0.275042 0.275042)
							(end -0.3048 0.2032)
						)
						(arc
							(start -0.3048 -0.2032)
							(mid -0.275042 -0.275042)
							(end -0.2032 -0.3048)
						)
						(arc
							(start 0.2032 -0.3048)
							(mid 0.275042 -0.275042)
							(end 0.3048 -0.2032)
						)
					)
					(width 0)
					(fill yes)
				)
			)
		)
	)
)
